(kicad_pcb
	(version 20260206)
	(generator "pcbnew")
	(generator_version "10.0")
	(general
		(thickness 0.77098)
		(legacy_teardrops no)
	)
	(paper "A4")
	(title_block
		(title "gnss-m2-zed-f9t — M2_ZED-F9T_MODULE.PcbDoc")
		(comment 1 "Time Appliance Project (Time Card) / footprints 28-31 of 36")
	)
	(layers
		(0 "F.Cu" signal "L01-Top Layer")
		(4 "In1.Cu" signal "L02-Inner Layer")
		(6 "In2.Cu" signal "L03-Inner Layer")
		(2 "B.Cu" signal "L04-Bottom Layer")
		(9 "F.Adhes" user "F.Adhesive")
		(11 "B.Adhes" user "B.Adhesive")
		(13 "F.Paste" user "Top Paste")
		(15 "B.Paste" user "Bottom Paste")
		(5 "F.SilkS" user "Top Overlay")
		(7 "B.SilkS" user "Bottom Overlay")
		(1 "F.Mask" user "Top Solder")
		(3 "B.Mask" user "Bottom Solder")
		(17 "Dwgs.User" user "User.Drawings")
		(19 "Cmts.User" user "User.Comments")
		(21 "Eco1.User" user "User.Eco1")
		(23 "Eco2.User" user "User.Eco2")
		(25 "Edge.Cuts" user)
		(27 "Margin" user)
		(31 "F.CrtYd" user "Top Courtyard")
		(29 "B.CrtYd" user "Bottom Courtyard")
		(35 "F.Fab" user "Top Component Outline")
		(33 "B.Fab" user "Bottom Component Outline 2")
	)
	(footprint "M2_Library:OCPTAP M2 FINGERS"
		(locked yes)
		(layer "F.Cu")
		(at 157.751105 124.7286)
		(property "Reference" "J1"
			(at -0.92017 -2.308125 0)
			(unlocked yes)
			(layer "F.SilkS")
			(effects
				(font
					(face "Arial")
					(size 0.40005 0.40005)
					(thickness 0.1778)
				)
			)
		)
		(property "Value" "OCPTAP_M2_FINGERS"
			(at 7.73093 8.439455 0)
			(unlocked yes)
			(layer "F.SilkS")
			(hide yes)
			(effects
				(font
					(face "Arial")
					(size 0.40005 0.40005)
					(thickness 0.1778)
				)
			)
		)
		(sheetname "03-M2_GoldFingers")
		(sheetfile "03-M2_GoldFingers.kicad_sch")
		(duplicate_pad_numbers_are_jumpers no)
		(fp_text user "75"
			(at -18.898 -1.525 270)
			(unlocked yes)
			(layer "F.SilkS")
			(effects
				(font
					(face "Arial")
					(size 0.315 0.315)
					(thickness 0.1)
				)
				(justify left bottom mirror)
			)
		)
		(fp_text user "21"
			(at -5.22855 -1.44955 270)
			(unlocked yes)
			(layer "F.SilkS")
			(effects
				(font
					(face "Arial")
					(size 0.315 0.315)
					(thickness 0.1)
				)
				(justify left bottom mirror)
			)
		)
		(fp_text user "11"
			(at -2.70871 -1.425 270)
			(unlocked yes)
			(layer "F.SilkS")
			(effects
				(font
					(face "Arial")
					(size 0.315 0.315)
					(thickness 0.1)
				)
				(justify left bottom mirror)
			)
		)
		(fp_text user "1"
			(at -0.29755 -1.375 270)
			(unlocked yes)
			(layer "F.SilkS")
			(effects
				(font
					(face "Arial")
					(size 0.315 0.315)
					(thickness 0.1)
				)
				(justify left bottom mirror)
			)
		)
		(fp_text user "74"
			(at -18.61125 -1.625 270)
			(unlocked yes)
			(layer "B.SilkS")
			(effects
				(font
					(size 0.5 0.5)
					(thickness 0.1)
				)
				(justify left bottom mirror)
			)
		)
		(fp_text user "20"
			(at -5.21125 -1.425 270)
			(unlocked yes)
			(layer "B.SilkS")
			(effects
				(font
					(size 0.5 0.5)
					(thickness 0.1)
				)
				(justify left bottom mirror)
			)
		)
		(fp_text user "10"
			(at -2.58039 -1.525 270)
			(unlocked yes)
			(layer "B.SilkS")
			(effects
				(font
					(size 0.5 0.5)
					(thickness 0.1)
				)
				(justify left bottom mirror)
			)
		)
		(fp_text user "2"
			(at -0.27841 -1.725 270)
			(unlocked yes)
			(layer "B.SilkS")
			(effects
				(font
					(size 0.5 0.5)
					(thickness 0.1)
				)
				(justify left bottom mirror)
			)
		)
		(pad "1" smd rect
			(at 0 0)
			(size 0.35 1.45)
			(layers "F.Cu" "F.Mask" "F.Paste")
		)
		(pad "2" smd rect
			(at -0.244 -0.25)
			(size 0.35 1.95)
			(layers "B.Cu" "B.Mask" "B.Paste")
			(net "+3V3")
		)
		(pad "3" smd rect
			(at -0.5 0)
			(size 0.35 1.45)
			(layers "F.Cu" "F.Mask" "F.Paste")
			(net "GND")
		)
		(pad "4" smd rect
			(at -0.744 -0.25)
			(size 0.35 1.95)
			(layers "B.Cu" "B.Mask" "B.Paste")
			(net "+3V3")
		)
		(pad "5" smd rect
			(at -1 0)
			(size 0.35 1.45)
			(layers "F.Cu" "F.Mask" "F.Paste")
			(net "GND")
		)
		(pad "6" smd rect
			(at -1.244 -0.25)
			(size 0.35 1.95)
			(layers "B.Cu" "B.Mask" "B.Paste")
		)
		(pad "7" smd rect
			(at -1.5 0)
			(size 0.35 1.45)
			(layers "F.Cu" "F.Mask" "F.Paste")
			(net "USB_D_P")
		)
		(pad "8" smd rect
			(at -1.744 -0.25)
			(size 0.35 1.95)
			(layers "B.Cu" "B.Mask" "B.Paste")
		)
		(pad "9" smd rect
			(at -2 0)
			(size 0.35 1.45)
			(layers "F.Cu" "F.Mask" "F.Paste")
			(net "USB_D_N")
		)
		(pad "10" smd rect
			(at -2.244 -0.25)
			(size 0.35 1.95)
			(layers "B.Cu" "B.Mask" "B.Paste")
		)
		(pad "11" smd rect
			(at -2.5 0)
			(size 0.35 1.45)
			(layers "F.Cu" "F.Mask" "F.Paste")
			(net "GND")
		)
		(pad "20" smd rect
			(at -4.744 -0.25)
			(size 0.35 1.95)
			(layers "B.Cu" "B.Mask" "B.Paste")
		)
		(pad "21" smd rect
			(at -5 0)
			(size 0.35 1.45)
			(layers "F.Cu" "F.Mask" "F.Paste")
			(net "GND")
		)
		(pad "22" smd rect
			(at -5.244 -0.25)
			(size 0.35 1.95)
			(layers "B.Cu" "B.Mask" "B.Paste")
		)
		(pad "23" smd rect
			(at -5.5 0)
			(size 0.35 1.45)
			(layers "F.Cu" "F.Mask" "F.Paste")
		)
		(pad "24" smd rect
			(at -5.744 -0.25)
			(size 0.35 1.95)
			(layers "B.Cu" "B.Mask" "B.Paste")
		)
		(pad "25" smd rect
			(at -6 0)
			(size 0.35 1.45)
			(layers "F.Cu" "F.Mask" "F.Paste")
		)
		(pad "26" smd rect
			(at -6.244 -0.25)
			(size 0.35 1.95)
			(layers "B.Cu" "B.Mask" "B.Paste")
		)
		(pad "27" smd rect
			(at -6.5 0)
			(size 0.35 1.45)
			(layers "F.Cu" "F.Mask" "F.Paste")
			(net "GND")
		)
		(pad "28" smd rect
			(at -6.744 -0.25)
			(size 0.35 1.95)
			(layers "B.Cu" "B.Mask" "B.Paste")
		)
		(pad "29" smd rect
			(at -7 0)
			(size 0.35 1.45)
			(layers "F.Cu" "F.Mask" "F.Paste")
		)
		(pad "30" smd rect
			(at -7.244 -0.25)
			(size 0.35 1.95)
			(layers "B.Cu" "B.Mask" "B.Paste")
		)
		(pad "31" smd rect
			(at -7.5 0)
			(size 0.35 1.45)
			(layers "F.Cu" "F.Mask" "F.Paste")
		)
		(pad "32" smd rect
			(at -7.744 -0.25)
			(size 0.35 1.95)
			(layers "B.Cu" "B.Mask" "B.Paste")
		)
		(pad "33" smd rect
			(at -8 0)
			(size 0.35 1.45)
			(layers "F.Cu" "F.Mask" "F.Paste")
			(net "GND")
		)
		(pad "34" smd rect
			(at -8.244 -0.25)
			(size 0.35 1.95)
			(layers "B.Cu" "B.Mask" "B.Paste")
		)
		(pad "35" smd rect
			(at -8.5 0)
			(size 0.35 1.45)
			(layers "F.Cu" "F.Mask" "F.Paste")
			(net "NetJ1_35")
		)
		(pad "36" smd rect
			(at -8.744 -0.25)
			(size 0.35 1.95)
			(layers "B.Cu" "B.Mask" "B.Paste")
		)
		(pad "37" smd rect
			(at -9 0)
			(size 0.35 1.45)
			(layers "F.Cu" "F.Mask" "F.Paste")
		)
		(pad "38" smd rect
			(at -9.244 -0.25)
			(size 0.35 1.95)
			(layers "B.Cu" "B.Mask" "B.Paste")
		)
		(pad "39" smd rect
			(at -9.5 0)
			(size 0.35 1.45)
			(layers "F.Cu" "F.Mask" "F.Paste")
			(net "GND")
		)
		(pad "40" smd rect
			(at -9.744 -0.25)
			(size 0.35 1.95)
			(layers "B.Cu" "B.Mask" "B.Paste")
			(net "SCL")
		)
		(pad "41" smd rect
			(at -10 0)
			(size 0.35 1.45)
			(layers "F.Cu" "F.Mask" "F.Paste")
		)
		(pad "42" smd rect
			(at -10.244 -0.25)
			(size 0.35 1.95)
			(layers "B.Cu" "B.Mask" "B.Paste")
			(net "SDA")
		)
		(pad "43" smd rect
			(at -10.5 0)
			(size 0.35 1.45)
			(layers "F.Cu" "F.Mask" "F.Paste")
		)
		(pad "44" smd rect
			(at -10.744 -0.25)
			(size 0.35 1.95)
			(layers "B.Cu" "B.Mask" "B.Paste")
		)
		(pad "45" smd rect
			(at -11 0)
			(size 0.35 1.45)
			(layers "F.Cu" "F.Mask" "F.Paste")
			(net "GND")
		)
		(pad "46" smd rect
			(at -11.244 -0.25)
			(size 0.35 1.95)
			(layers "B.Cu" "B.Mask" "B.Paste")
			(net "NetJ1_46")
		)
		(pad "47" smd rect
			(at -11.5 0)
			(size 0.35 1.45)
			(layers "F.Cu" "F.Mask" "F.Paste")
		)
		(pad "48" smd rect
			(at -11.744 -0.25)
			(size 0.35 1.95)
			(layers "B.Cu" "B.Mask" "B.Paste")
		)
		(pad "49" smd rect
			(at -12 0)
			(size 0.35 1.45)
			(layers "F.Cu" "F.Mask" "F.Paste")
		)
		(pad "50" smd rect
			(at -12.244 -0.25)
			(size 0.35 1.95)
			(layers "B.Cu" "B.Mask" "B.Paste")
			(net "NetJ1_50")
		)
		(pad "51" smd rect
			(at -12.5 0)
			(size 0.35 1.45)
			(layers "F.Cu" "F.Mask" "F.Paste")
			(net "GND")
		)
		(pad "52" smd rect
			(at -12.744 -0.25)
			(size 0.35 1.95)
			(layers "B.Cu" "B.Mask" "B.Paste")
		)
		(pad "53" smd rect
			(at -13 0)
			(size 0.35 1.45)
			(layers "F.Cu" "F.Mask" "F.Paste")
		)
		(pad "54" smd rect
			(at -13.244 -0.25)
			(size 0.35 1.95)
			(layers "B.Cu" "B.Mask" "B.Paste")
		)
		(pad "55" smd rect
			(at -13.5 0)
			(size 0.35 1.45)
			(layers "F.Cu" "F.Mask" "F.Paste")
		)
		(pad "56" smd rect
			(at -13.744 -0.25)
			(size 0.35 1.95)
			(layers "B.Cu" "B.Mask" "B.Paste")
		)
		(pad "57" smd rect
			(at -14 0)
			(size 0.35 1.45)
			(layers "F.Cu" "F.Mask" "F.Paste")
			(net "GND")
		)
		(pad "58" smd rect
			(at -14.244 -0.25)
			(size 0.35 1.95)
			(layers "B.Cu" "B.Mask" "B.Paste")
		)
		(pad "59" smd rect
			(at -14.5 0)
			(size 0.35 1.45)
			(layers "F.Cu" "F.Mask" "F.Paste")
		)
		(pad "60" smd rect
			(at -14.744 -0.25)
			(size 0.35 1.95)
			(layers "B.Cu" "B.Mask" "B.Paste")
		)
		(pad "61" smd rect
			(at -15 0)
			(size 0.35 1.45)
			(layers "F.Cu" "F.Mask" "F.Paste")
		)
		(pad "62" smd rect
			(at -15.244 -0.25)
			(size 0.35 1.95)
			(layers "B.Cu" "B.Mask" "B.Paste")
			(net "RX_GPS_CONN")
		)
		(pad "63" smd rect
			(at -15.5 0)
			(size 0.35 1.45)
			(layers "F.Cu" "F.Mask" "F.Paste")
		)
		(pad "64" smd rect
			(at -15.744 -0.25)
			(size 0.35 1.95)
			(layers "B.Cu" "B.Mask" "B.Paste")
			(net "TX_GPS_CONN")
		)
		(pad "65" smd rect
			(at -16 0)
			(size 0.35 1.45)
			(layers "F.Cu" "F.Mask" "F.Paste")
		)
		(pad "66" smd rect
			(at -16.244 -0.25)
			(size 0.35 1.95)
			(layers "B.Cu" "B.Mask" "B.Paste")
		)
		(pad "67" smd rect
			(at -16.5 0)
			(size 0.35 1.45)
			(layers "F.Cu" "F.Mask" "F.Paste")
			(net "NetJ1_67")
		)
		(pad "68" smd rect
			(at -16.744 -0.25)
			(size 0.35 1.95)
			(layers "B.Cu" "B.Mask" "B.Paste")
		)
		(pad "69" smd rect
			(at -17 0)
			(size 0.35 1.45)
			(layers "F.Cu" "F.Mask" "F.Paste")
		)
		(pad "70" smd rect
			(at -17.244 -0.25)
			(size 0.35 1.95)
			(layers "B.Cu" "B.Mask" "B.Paste")
			(net "+3V3")
		)
		(pad "71" smd rect
			(at -17.5 0)
			(size 0.35 1.45)
			(layers "F.Cu" "F.Mask" "F.Paste")
			(net "GND")
		)
		(pad "72" smd rect
			(at -17.744 -0.25)
			(size 0.35 1.95)
			(layers "B.Cu" "B.Mask" "B.Paste")
			(net "+3V3")
		)
		(pad "73" smd rect
			(at -18 0)
			(size 0.35 1.45)
			(layers "F.Cu" "F.Mask" "F.Paste")
			(net "GND")
		)
		(pad "74" smd rect
			(at -18.244 -0.25)
			(size 0.35 1.95)
			(layers "B.Cu" "B.Mask" "B.Paste")
			(net "+3V3")
		)
		(pad "75" smd rect
			(at -18.5 0)
			(size 0.35 1.45)
			(layers "F.Cu" "F.Mask" "F.Paste")
			(net "GND")
		)
	)
	(footprint "Vault:RESC1005X40X25NL05T10"
		(layer "F.Cu")
		(at 145.401105 115.9036 180)
		(property "Reference" "R3"
			(at 2.1 -0.016875 0)
			(unlocked yes)
			(layer "F.SilkS")
			(effects
				(font
					(face "Arial")
					(size 0.40005 0.40005)
					(thickness 0.1778)
				)
			)
		)
		(property "Value" "0_5%_0402"
			(at 4.760695 2.013255 180)
			(unlocked yes)
			(layer "F.SilkS")
			(hide yes)
			(effects
				(font
					(face "Arial")
					(size 0.40005 0.40005)
					(thickness 0.1778)
				)
			)
		)
		(sheetname "01-M2_ZED-F9T_MODULE")
		(sheetfile "01-M2_ZED-F9T_MODULE.kicad_sch")
		(duplicate_pad_numbers_are_jumpers no)
		(fp_line
			(start 0.9 0.45)
			(end -0.9 0.45)
			(stroke
				(width 0.05)
				(type solid)
			)
			(layer "F.CrtYd")
		)
		(fp_line
			(start 0.9 -0.45)
			(end 0.9 0.45)
			(stroke
				(width 0.05)
				(type solid)
			)
			(layer "F.CrtYd")
		)
		(fp_line
			(start 0.9 -0.45)
			(end -0.9 -0.45)
			(stroke
				(width 0.05)
				(type solid)
			)
			(layer "F.CrtYd")
		)
		(fp_line
			(start 0.275 0)
			(end -0.275 0)
			(stroke
				(width 0.1)
				(type solid)
			)
			(layer "F.CrtYd")
		)
		(fp_line
			(start 0 -0.275)
			(end 0 0.275)
			(stroke
				(width 0.1)
				(type solid)
			)
			(layer "F.CrtYd")
		)
		(fp_line
			(start -0.9 -0.45)
			(end -0.9 0.45)
			(stroke
				(width 0.05)
				(type solid)
			)
			(layer "F.CrtYd")
		)
		(pad "1" smd rect
			(at -0.425 0 270)
			(size 0.55 0.6)
			(layers "F.Cu" "F.Mask" "F.Paste")
			(net "RX_GPS_CONN")
		)
		(pad "2" smd rect
			(at 0.425 0 270)
			(size 0.55 0.6)
			(layers "F.Cu" "F.Mask" "F.Paste")
			(net "NetR3_2")
		)
	)
	(footprint "Vault:FP-RMCF0402-MFG"
		(layer "F.Cu")
		(at 140.201105 112.9036 180)
		(property "Reference" "R7"
			(at 0 1.180485 0)
			(unlocked yes)
			(layer "F.SilkS")
			(effects
				(font
					(face "Arial")
					(size 0.40005 0.40005)
					(thickness 0.178)
				)
			)
		)
		(property "Value" "1k"
			(at 6.53812 1.956021 180)
			(unlocked yes)
			(layer "F.SilkS")
			(hide yes)
			(effects
				(font
					(face "Arial")
					(size 0.96012 0.96012)
					(thickness 0.254)
				)
			)
		)
		(sheetname "01-M2_ZED-F9T_MODULE")
		(sheetfile "01-M2_ZED-F9T_MODULE.kicad_sch")
		(duplicate_pad_numbers_are_jumpers no)
		(fp_line
			(start 0.55 0.7)
			(end -0.55 0.7)
			(stroke
				(width 0.2)
				(type solid)
			)
			(layer "F.SilkS")
		)
		(fp_line
			(start 0.55 -0.7)
			(end -0.55 -0.7)
			(stroke
				(width 0.2)
				(type solid)
			)
			(layer "F.SilkS")
		)
		(fp_line
			(start 0.85 0.4)
			(end -0.85 0.4)
			(stroke
				(width 0.2)
				(type solid)
			)
			(layer "F.CrtYd")
		)
		(fp_line
			(start 0.85 -0.4)
			(end 0.85 0.4)
			(stroke
				(width 0.2)
				(type solid)
			)
			(layer "F.CrtYd")
		)
		(fp_line
			(start 0.85 -0.4)
			(end -0.85 -0.4)
			(stroke
				(width 0.2)
				(type solid)
			)
			(layer "F.CrtYd")
		)
		(fp_line
			(start -0.85 -0.4)
			(end -0.85 0.4)
			(stroke
				(width 0.2)
				(type solid)
			)
			(layer "F.CrtYd")
		)
		(fp_line
			(start 0.85 0.4)
			(end -0.85 0.4)
			(stroke
				(width 0.2)
				(type solid)
			)
			(layer "F.Fab")
		)
		(fp_line
			(start 0.85 -0.4)
			(end 0.85 0.4)
			(stroke
				(width 0.2)
				(type solid)
			)
			(layer "F.Fab")
		)
		(fp_line
			(start 0.85 -0.4)
			(end -0.85 -0.4)
			(stroke
				(width 0.2)
				(type solid)
			)
			(layer "F.Fab")
		)
		(fp_line
			(start 0.5 0)
			(end -0.5 0)
			(stroke
				(width 0.1)
				(type solid)
			)
			(layer "F.Fab")
		)
		(fp_line
			(start 0 -0.5)
			(end 0 0.5)
			(stroke
				(width 0.1)
				(type solid)
			)
			(layer "F.Fab")
		)
		(fp_line
			(start -0.85 -0.4)
			(end -0.85 0.4)
			(stroke
				(width 0.2)
				(type solid)
			)
			(layer "F.Fab")
		)
		(fp_text user "${REFERENCE}"
			(at -0.00001 0.10711 180)
			(unlocked yes)
			(layer "F.Fab")
			(effects
				(font
					(face "Arial")
					(size 0.63 0.63)
					(thickness 0.1)
				)
				(justify left bottom)
			)
		)
		(pad "1" smd rect
			(at -0.5 0 180)
			(size 0.5 0.6)
			(layers "F.Cu" "F.Mask" "F.Paste")
			(net "GND")
			(solder_mask_margin 0)
			(solder_paste_margin 0)
		)
		(pad "2" smd rect
			(at 0.5 0 180)
			(size 0.5 0.6)
			(layers "F.Cu" "F.Mask" "F.Paste")
			(net "NetD3_1")
			(solder_mask_margin 0)
			(solder_paste_margin 0)
		)
	)
	(footprint "Vault:FP-RMCF0402-MFG"
		(layer "F.Cu")
		(at 145.701105 88.6786)
		(property "Reference" "R10"
			(at 0.549995 -1.158125 0)
			(unlocked yes)
			(layer "F.SilkS")
			(effects
				(font
					(face "Arial")
					(size 0.40005 0.40005)
					(thickness 0.1778)
				)
			)
		)
		(property "Value" "1k"
			(at 2.729345 2.066945 0)
			(unlocked yes)
			(layer "F.SilkS")
			(hide yes)
			(effects
				(font
					(face "Arial")
					(size 0.40005 0.40005)
					(thickness 0.1778)
				)
			)
		)
		(sheetname "02-Antenna_Supervisor")
		(sheetfile "02-Antenna_Supervisor.kicad_sch")
		(duplicate_pad_numbers_are_jumpers no)
		(fp_line
			(start -0.85 -0.4)
			(end 0.85 -0.4)
			(stroke
				(width 0.2)
				(type solid)
			)
			(layer "F.CrtYd")
		)
		(fp_line
			(start -0.85 0.4)
			(end -0.85 -0.4)
			(stroke
				(width 0.2)
				(type solid)
			)
			(layer "F.CrtYd")
		)
		(fp_line
			(start -0.85 0.4)
			(end 0.85 0.4)
			(stroke
				(width 0.2)
				(type solid)
			)
			(layer "F.CrtYd")
		)
		(fp_line
			(start 0.85 0.4)
			(end 0.85 -0.4)
			(stroke
				(width 0.2)
				(type solid)
			)
			(layer "F.CrtYd")
		)
		(fp_line
			(start -0.85 -0.4)
			(end 0.85 -0.4)
			(stroke
				(width 0.2)
				(type solid)
			)
			(layer "F.Fab")
		)
		(fp_line
			(start -0.85 0.4)
			(end -0.85 -0.4)
			(stroke
				(width 0.2)
				(type solid)
			)
			(layer "F.Fab")
		)
		(fp_line
			(start -0.85 0.4)
			(end 0.85 0.4)
			(stroke
				(width 0.2)
				(type solid)
			)
			(layer "F.Fab")
		)
		(fp_line
			(start -0.5 0)
			(end 0.5 0)
			(stroke
				(width 0.1)
				(type solid)
			)
			(layer "F.Fab")
		)
		(fp_line
			(start 0 0.5)
			(end 0 -0.5)
			(stroke
				(width 0.1)
				(type solid)
			)
			(layer "F.Fab")
		)
		(fp_line
			(start 0.85 0.4)
			(end 0.85 -0.4)
			(stroke
				(width 0.2)
				(type solid)
			)
			(layer "F.Fab")
		)
		(fp_text user "${REFERENCE}"
			(at -0.00001 0.09602 360)
			(unlocked yes)
			(layer "F.Fab")
			(effects
				(font
					(face "Arial")
					(size 0.63 0.63)
					(thickness 0.1)
				)
				(justify left bottom)
			)
		)
		(pad "1" smd rect
			(at -0.5 0)
			(size 0.5 0.6)
			(layers "F.Cu" "F.Mask" "F.Paste")
			(net "NetR10_1")
			(solder_mask_margin 0)
			(solder_paste_margin 0)
		)
		(pad "2" smd rect
			(at 0.5 0)
			(size 0.5 0.6)
			(layers "F.Cu" "F.Mask" "F.Paste")
			(net "NetQ1_3")
			(solder_mask_margin 0)
			(solder_paste_margin 0)
		)
	)
)
